(kicad_pcb
	(version 20260206)
	(generator "pcbnew")
	(generator_version "10.0")
	(general
		(thickness 1.6)
		(legacy_teardrops no)
	)
	(paper "A4")
	(title_block
		(title "Bryce Canyon_F.DPB_16315-1-OCP.brd")
		(comment 1 "Bryce Canyon / footprints 1735-1740 of 2223")
	)
	(layers
		(0 "F.Cu" signal "TOP")
		(4 "In1.Cu" signal "L2GND")
		(6 "In2.Cu" signal "L3")
		(8 "In3.Cu" signal "L4GND")
		(10 "In4.Cu" signal "L5")
		(12 "In5.Cu" signal "L6VCC")
		(14 "In6.Cu" signal "L7VCC")
		(16 "In7.Cu" signal "L8")
		(18 "In8.Cu" signal "L9GND")
		(20 "In9.Cu" signal "L10")
		(22 "In10.Cu" signal "L11GND")
		(2 "B.Cu" signal "BOTTOM")
		(9 "F.Adhes" user "F.Adhesive")
		(11 "B.Adhes" user "B.Adhesive")
		(13 "F.Paste" user "Package Geometry/Pastemask Top")
		(15 "B.Paste" user "Package Geometry/Pastemask Bottom")
		(5 "F.SilkS" user "Ref Des/Silkscreen Top")
		(7 "B.SilkS" user "Ref Des/Silkscreen Bottom")
		(1 "F.Mask" user "Board Geometry/Soldermask Top")
		(3 "B.Mask" user "Board Geometry/Soldermask Bottom")
		(17 "Dwgs.User" user "User.Drawings")
		(19 "Cmts.User" user "User.Comments")
		(21 "Eco1.User" user "User.Eco1")
		(23 "Eco2.User" user "User.Eco2")
		(25 "Edge.Cuts" user "Board Geometry/Outline")
		(27 "Margin" user)
		(31 "F.CrtYd" user "Package Geometry/Place Bound Top")
		(29 "B.CrtYd" user "Package Geometry/Place Bound Bottom")
		(35 "F.Fab" user "Ref Des/Assembly Top")
		(33 "B.Fab" user "Ref Des/Assembly Bottom")
	)
	(footprint ""
		(layer "F.Cu")
		(at 244.200172 -360.205528)
		(property "Reference" ""
			(at 0 0 0)
			(layer "F.SilkS")
			(hide yes)
			(effects
				(font
					(size 1.27 1.27)
				)
			)
		)
		(property "Value" "*"
			(at -8.398764 -8.057642 0)
			(unlocked yes)
			(layer "F.Fab")
			(hide yes)
			(effects
				(font
					(size 1.016 1.016)
					(thickness 0.1524)
				)
			)
		)
		(duplicate_pad_numbers_are_jumpers no)
		(fp_poly
			(pts
				(arc
					(start 7.3152 0)
					(mid 0 7.3152)
					(end -7.3152 0)
				)
				(arc
					(start -7.3152 -5.9944)
					(mid 0 -13.3096)
					(end 7.3152 -5.9944)
				)
			)
			(stroke
				(width 0)
				(type default)
			)
			(fill no)
			(layer "B.CrtYd")
		)
		(fp_poly
			(pts
				(arc
					(start 7.3152 0)
					(mid 0 7.3152)
					(end -7.3152 0)
				)
				(arc
					(start -7.3152 -5.9944)
					(mid 0 -13.3096)
					(end 7.3152 -5.9944)
				)
			)
			(stroke
				(width 0)
				(type default)
			)
			(fill no)
			(layer "F.CrtYd")
		)
		(fp_poly
			(pts
				(arc
					(start 7.3152 0)
					(mid 0 7.3152)
					(end -7.3152 0)
				)
				(arc
					(start -7.3152 -5.9944)
					(mid 0 -13.3096)
					(end 7.3152 -5.9944)
				)
			)
			(stroke
				(width 0)
				(type default)
			)
			(fill no)
			(layer "B.Fab")
		)
		(fp_poly
			(pts
				(arc
					(start 7.3152 0)
					(mid 0 7.3152)
					(end -7.3152 0)
				)
				(arc
					(start -7.3152 -5.9944)
					(mid 0 -13.3096)
					(end 7.3152 -5.9944)
				)
			)
			(stroke
				(width 0)
				(type default)
			)
			(fill no)
			(layer "F.Fab")
		)
		(pad "1" thru_hole oval
			(at 0 0)
			(size 14.0208 20.0152)
			(drill 0.0254
				(offset 0 -2.9972)
			)
			(layers "*.Cu" "*.Mask")
			(remove_unused_layers no)
			(net "Net_69")
			(clearance -1.002284)
			(thermal_gap 0.1524)
			(padstack
				(mode front_inner_back)
				(layer "Inner"
					(shape custom)
					(size 2.928012 2.928012)
					(options
						(anchor circle)
					)
					(primitives
						(gr_poly
							(pts
								(arc
									(start 4.571746 -2.084324)
									(mid 0.000333 7.430372)
									(end -4.571492 -2.084324)
								)
								(arc
									(start -4.571492 -2.084324)
									(mid -3.570296 -3.611977)
									(end -2.875026 -5.30098)
								)
								(arc
									(start -2.875026 -5.30098)
									(mid 0.000217 -7.43089)
									(end 2.87528 -5.30098)
								)
								(arc
									(start 2.87528 -5.30098)
									(mid 3.570511 -3.611956)
									(end 4.571746 -2.084324)
								)
							)
							(width 0)
							(fill yes)
						)
					)
					(clearance 0.1524)
				)
				(layer "B.Cu"
					(shape oval)
					(size 14.0208 20.0152)
					(offset 0 -2.9972)
					(clearance -1.002284)
				)
			)
		)
		(zone
			(layers "F.Cu" "B.Cu" "In1.Cu" "In2.Cu" "In3.Cu" "In4.Cu" "In5.Cu" "In6.Cu"
				"In7.Cu" "In8.Cu" "In9.Cu" "In10.Cu"
			)
			(hatch none 0.5)
			(connect_pads
				(clearance 0)
			)
			(min_thickness 0.25)
			(keepout
				(tracks not_allowed)
				(vias allowed)
				(pads allowed)
				(copperpour not_allowed)
				(footprints allowed)
			)
			(placement
				(enabled no)
				(sheetname "")
			)
			(fill
				(thermal_gap 0.5)
				(thermal_bridge_width 0.5)
				(island_removal_mode 0)
			)
			(polygon
				(pts
					(arc
						(start 237.189772 -366.199928)
						(mid 244.200172 -373.210328)
						(end 251.210572 -366.199928)
					)
					(arc
						(start 251.210572 -360.205528)
						(mid 244.200172 -353.195128)
						(end 237.189772 -360.205528)
					)
				)
			)
		)
	)
	(footprint ""
		(layer "F.Cu")
		(at 83.255866 -18.50263 -90)
		(property "Reference" "R63"
			(at 0 0 270)
			(layer "F.SilkS")
			(hide yes)
			(effects
				(font
					(size 1.27 1.27)
				)
			)
		)
		(property "Value" "4K7R2F-GP"
			(at 0.064008 -3.993896 270)
			(unlocked yes)
			(layer "F.Fab")
			(hide yes)
			(effects
				(font
					(size 1.016 1.016)
					(thickness 0.1524)
				)
			)
		)
		(property "Device Type" "R402H16"
			(at 0.064008 -5.517896 270)
			(unlocked yes)
			(layer "F.Fab")
			(hide yes)
			(effects
				(font
					(size 1.016 1.016)
					(thickness 0.1524)
				)
			)
		)
		(duplicate_pad_numbers_are_jumpers no)
		(fp_line
			(start -0.508 -0.9398)
			(end -0.508 0.9398)
			(stroke
				(width 0.1524)
				(type default)
			)
			(layer "F.SilkS")
		)
		(fp_line
			(start 0.508 -0.9398)
			(end -0.508 -0.9398)
			(stroke
				(width 0.1524)
				(type default)
			)
			(layer "F.SilkS")
		)
		(fp_rect
			(start -0.508 0.9398)
			(end 0.508 -0.9398)
			(stroke
				(width 0)
				(type default)
			)
			(fill no)
			(layer "F.CrtYd")
		)
		(fp_rect
			(start -0.508 0.9398)
			(end 0.508 -0.9398)
			(stroke
				(width 0)
				(type default)
			)
			(fill no)
			(layer "F.Fab")
		)
		(pad "1" smd custom
			(at 0 -0.4445 270)
			(size 0.1397 0.1397)
			(layers "F.Cu" "F.Mask" "F.Paste")
			(net "IO_EXP10_A2")
			(options
				(clearance outline)
				(anchor circle)
			)
			(primitives
				(gr_poly
					(pts
						(arc
							(start -0.1778 -0.2794)
							(mid -0.249642 -0.249642)
							(end -0.2794 -0.1778)
						)
						(arc
							(start -0.2794 0.1778)
							(mid -0.249642 0.249642)
							(end -0.1778 0.2794)
						)
						(arc
							(start 0.1778 0.2794)
							(mid 0.249642 0.249642)
							(end 0.2794 0.1778)
						)
						(arc
							(start 0.2794 -0.1778)
							(mid 0.249642 -0.249642)
							(end 0.1778 -0.2794)
						)
					)
					(width 0)
					(fill yes)
				)
			)
		)
		(pad "2" smd custom
			(at 0 0.4445 270)
			(size 0.1397 0.1397)
			(layers "F.Cu" "F.Mask" "F.Paste")
			(net "GND")
			(options
				(clearance outline)
				(anchor circle)
			)
			(primitives
				(gr_poly
					(pts
						(arc
							(start -0.1778 -0.2794)
							(mid -0.249642 -0.249642)
							(end -0.2794 -0.1778)
						)
						(arc
							(start -0.2794 0.1778)
							(mid -0.249642 0.249642)
							(end -0.1778 0.2794)
						)
						(arc
							(start 0.1778 0.2794)
							(mid 0.249642 0.249642)
							(end 0.2794 0.1778)
						)
						(arc
							(start 0.2794 -0.1778)
							(mid 0.249642 -0.249642)
							(end 0.1778 -0.2794)
						)
					)
					(width 0)
					(fill yes)
				)
			)
		)
	)
	(footprint ""
		(layer "F.Cu")
		(at 141.423898 -277.183342 180)
		(property "Reference" "R238"
			(at 0 0 180)
			(layer "F.SilkS")
			(hide yes)
			(effects
				(font
					(size 1.27 1.27)
				)
			)
		)
		(property "Value" "200KR2F-L-GP"
			(at 0.064008 -3.993896 180)
			(unlocked yes)
			(layer "F.Fab")
			(hide yes)
			(effects
				(font
					(size 1.016 1.016)
					(thickness 0.1524)
				)
			)
		)
		(property "Device Type" "R402H16"
			(at 0.064008 -5.517896 180)
			(unlocked yes)
			(layer "F.Fab")
			(hide yes)
			(effects
				(font
					(size 1.016 1.016)
					(thickness 0.1524)
				)
			)
		)
		(duplicate_pad_numbers_are_jumpers no)
		(fp_line
			(start 0.508 -0.9398)
			(end -0.508 -0.9398)
			(stroke
				(width 0.1524)
				(type default)
			)
			(layer "F.SilkS")
		)
		(fp_line
			(start -0.508 -0.9398)
			(end -0.508 0.9398)
			(stroke
				(width 0.1524)
				(type default)
			)
			(layer "F.SilkS")
		)
		(fp_rect
			(start -0.508 0.9398)
			(end 0.508 -0.9398)
			(stroke
				(width 0)
				(type default)
			)
			(fill no)
			(layer "F.CrtYd")
		)
		(fp_rect
			(start -0.508 0.9398)
			(end 0.508 -0.9398)
			(stroke
				(width 0)
				(type default)
			)
			(fill no)
			(layer "F.Fab")
		)
		(pad "1" smd custom
			(at 0 -0.4445 180)
			(size 0.1397 0.1397)
			(layers "F.Cu" "F.Mask" "F.Paste")
			(net "SW_HDD_R4")
			(options
				(clearance outline)
				(anchor circle)
			)
			(primitives
				(gr_poly
					(pts
						(arc
							(start -0.1778 -0.2794)
							(mid -0.249642 -0.249642)
							(end -0.2794 -0.1778)
						)
						(arc
							(start -0.2794 0.1778)
							(mid -0.249642 0.249642)
							(end -0.1778 0.2794)
						)
						(arc
							(start 0.1778 0.2794)
							(mid 0.249642 0.249642)
							(end 0.2794 0.1778)
						)
						(arc
							(start 0.2794 -0.1778)
							(mid 0.249642 -0.249642)
							(end 0.1778 -0.2794)
						)
					)
					(width 0)
					(fill yes)
				)
			)
		)
		(pad "2" smd custom
			(at 0 0.4445 180)
			(size 0.1397 0.1397)
			(layers "F.Cu" "F.Mask" "F.Paste")
			(net "SW_HDD_N4")
			(options
				(clearance outline)
				(anchor circle)
			)
			(primitives
				(gr_poly
					(pts
						(arc
							(start -0.1778 -0.2794)
							(mid -0.249642 -0.249642)
							(end -0.2794 -0.1778)
						)
						(arc
							(start -0.2794 0.1778)
							(mid -0.249642 0.249642)
							(end -0.1778 0.2794)
						)
						(arc
							(start 0.1778 0.2794)
							(mid 0.249642 0.249642)
							(end 0.2794 0.1778)
						)
						(arc
							(start 0.2794 -0.1778)
							(mid 0.249642 -0.249642)
							(end 0.1778 -0.2794)
						)
					)
					(width 0)
					(fill yes)
				)
			)
		)
	)
	(footprint ""
		(layer "F.Cu")
		(at 474.4974 -269.367)
		(property "Reference" "R395"
			(at 0 0 0)
			(layer "F.SilkS")
			(hide yes)
			(effects
				(font
					(size 1.27 1.27)
				)
			)
		)
		(property "Value" "4K7R2J-2-GP"
			(at 0.064008 -3.993896 0)
			(unlocked yes)
			(layer "F.Fab")
			(hide yes)
			(effects
				(font
					(size 1.016 1.016)
					(thickness 0.1524)
				)
			)
		)
		(property "Device Type" "R402H16"
			(at 0.064008 -5.517896 0)
			(unlocked yes)
			(layer "F.Fab")
			(hide yes)
			(effects
				(font
					(size 1.016 1.016)
					(thickness 0.1524)
				)
			)
		)
		(duplicate_pad_numbers_are_jumpers no)
		(fp_line
			(start -0.508 -0.9398)
			(end -0.508 0.9398)
			(stroke
				(width 0.1524)
				(type default)
			)
			(layer "F.SilkS")
		)
		(fp_line
			(start 0.508 -0.9398)
			(end -0.508 -0.9398)
			(stroke
				(width 0.1524)
				(type default)
			)
			(layer "F.SilkS")
		)
		(fp_rect
			(start -0.508 0.9398)
			(end 0.508 -0.9398)
			(stroke
				(width 0)
				(type default)
			)
			(fill no)
			(layer "F.CrtYd")
		)
		(fp_rect
			(start -0.508 0.9398)
			(end 0.508 -0.9398)
			(stroke
				(width 0)
				(type default)
			)
			(fill no)
			(layer "F.Fab")
		)
		(pad "1" smd custom
			(at 0 -0.4445)
			(size 0.1397 0.1397)
			(layers "F.Cu" "F.Mask" "F.Paste")
			(net "SW_PWR_R_HDD11")
			(options
				(clearance outline)
				(anchor circle)
			)
			(primitives
				(gr_poly
					(pts
						(arc
							(start -0.1778 -0.2794)
							(mid -0.249642 -0.249642)
							(end -0.2794 -0.1778)
						)
						(arc
							(start -0.2794 0.1778)
							(mid -0.249642 0.249642)
							(end -0.1778 0.2794)
						)
						(arc
							(start 0.1778 0.2794)
							(mid 0.249642 0.249642)
							(end 0.2794 0.1778)
						)
						(arc
							(start 0.2794 -0.1778)
							(mid 0.249642 -0.249642)
							(end 0.1778 -0.2794)
						)
					)
					(width 0)
					(fill yes)
				)
			)
		)
		(pad "2" smd custom
			(at 0 0.4445)
			(size 0.1397 0.1397)
			(layers "F.Cu" "F.Mask" "F.Paste")
			(net "GND")
			(options
				(clearance outline)
				(anchor circle)
			)
			(primitives
				(gr_poly
					(pts
						(arc
							(start -0.1778 -0.2794)
							(mid -0.249642 -0.249642)
							(end -0.2794 -0.1778)
						)
						(arc
							(start -0.2794 0.1778)
							(mid -0.249642 0.249642)
							(end -0.1778 0.2794)
						)
						(arc
							(start 0.1778 0.2794)
							(mid 0.249642 0.249642)
							(end 0.2794 0.1778)
						)
						(arc
							(start 0.2794 -0.1778)
							(mid 0.249642 -0.249642)
							(end 0.1778 -0.2794)
						)
					)
					(width 0)
					(fill yes)
				)
			)
		)
	)
	(footprint ""
		(layer "F.Cu")
		(at 20.684998 -55.285894 180)
		(property "Reference" "Q144"
			(at 0 0 180)
			(layer "F.SilkS")
			(hide yes)
			(effects
				(font
					(size 1.27 1.27)
				)
			)
		)
		(property "Value" "AO4406AL-GP"
			(at -3.707384 -1.5367 180)
			(unlocked yes)
			(layer "F.Fab")
			(hide yes)
			(effects
				(font
					(size 1.016 1.016)
					(thickness 0.1524)
				)
			)
		)
		(property "Device Type" "SOIC8H69"
			(at -3.707384 -3.0607 180)
			(unlocked yes)
			(layer "F.Fab")
			(hide yes)
			(effects
				(font
					(size 1.016 1.016)
					(thickness 0.1524)
				)
			)
		)
		(duplicate_pad_numbers_are_jumpers no)
		(fp_line
			(start 2.1336 1.4224)
			(end 2.1336 -1.4224)
			(stroke
				(width 0.1524)
				(type default)
			)
			(layer "F.SilkS")
		)
		(fp_line
			(start 2.1336 -1.4224)
			(end -2.7432 -1.4224)
			(stroke
				(width 0.1524)
				(type default)
			)
			(layer "F.SilkS")
		)
		(fp_line
			(start -2.1844 -0.0508)
			(end -2.7178 0.508)
			(stroke
				(width 0.1524)
				(type default)
			)
			(layer "F.SilkS")
		)
		(fp_line
			(start -2.6289 3.4417)
			(end -2.6289 1.4732)
			(stroke
				(width 0.381)
				(type default)
			)
			(layer "F.SilkS")
		)
		(fp_line
			(start -2.7178 -0.508)
			(end -2.1844 -0.0508)
			(stroke
				(width 0.1524)
				(type default)
			)
			(layer "F.SilkS")
		)
		(fp_line
			(start -2.7432 1.4224)
			(end 2.1336 1.4224)
			(stroke
				(width 0.1524)
				(type default)
			)
			(layer "F.SilkS")
		)
		(fp_line
			(start -2.7432 1.4224)
			(end -2.6416 1.4224)
			(stroke
				(width 0.1524)
				(type default)
			)
			(layer "F.SilkS")
		)
		(fp_line
			(start -2.7432 -1.4224)
			(end -2.7432 1.4224)
			(stroke
				(width 0.1524)
				(type default)
			)
			(layer "F.SilkS")
		)
		(fp_poly
			(pts
				(xy -2.2098 -1.4224) (xy -2.2098 1.4224) (xy 2.2098 1.4224) (xy 2.2098 -1.4224)
			)
			(stroke
				(width 0)
				(type default)
			)
			(fill yes)
			(layer "F.SilkS")
		)
		(fp_rect
			(start -2.450084 2.999994)
			(end 2.450084 -2.999994)
			(stroke
				(width 0)
				(type default)
			)
			(fill no)
			(layer "F.CrtYd")
		)
		(fp_poly
			(pts
				(xy -2.8194 3.6322) (xy -2.8194 -3.6322) (xy 2.8194 -3.6322) (xy 2.8194 1.18364) (xy 2.450084 1.18364)
				(xy 2.450084 -2.999994) (xy -2.450084 -2.999994) (xy -2.450084 2.999994) (xy 2.450084 2.999994)
				(xy 2.450084 1.18618) (xy 2.8194 1.18618) (xy 2.8194 3.6322)
			)
			(stroke
				(width 0)
				(type default)
			)
			(fill no)
			(layer "F.CrtYd")
		)
		(fp_rect
			(start -2.8194 3.6322)
			(end 2.8194 -3.6322)
			(stroke
				(width 0)
				(type default)
			)
			(fill no)
			(layer "F.Fab")
		)
		(pad "1" smd rect
			(at -1.905 2.54 180)
			(size 0.635 1.651)
			(layers "F.Cu" "F.Mask" "F.Paste")
			(net "P5V_HDD24")
		)
		(pad "2" smd rect
			(at -0.635 2.54 180)
			(size 0.635 1.651)
			(layers "F.Cu" "F.Mask" "F.Paste")
			(net "P5V_HDD24")
		)
		(pad "3" smd rect
			(at 0.635 2.54 180)
			(size 0.635 1.651)
			(layers "F.Cu" "F.Mask" "F.Paste")
			(net "P5V_HDD24")
		)
		(pad "4" smd rect
			(at 1.905 2.54 180)
			(size 0.635 1.651)
			(layers "F.Cu" "F.Mask" "F.Paste")
			(net "SW_HDD_P24")
		)
		(pad "5" smd rect
			(at 1.905 -2.54 180)
			(size 0.635 1.651)
			(layers "F.Cu" "F.Mask" "F.Paste")
			(net "P5V_A_2")
		)
		(pad "6" smd rect
			(at 0.635 -2.54 180)
			(size 0.635 1.651)
			(layers "F.Cu" "F.Mask" "F.Paste")
			(net "P5V_A_2")
		)
		(pad "7" smd rect
			(at -0.635 -2.54 180)
			(size 0.635 1.651)
			(layers "F.Cu" "F.Mask" "F.Paste")
			(net "P5V_A_2")
		)
		(pad "8" smd rect
			(at -1.905 -2.54 180)
			(size 0.635 1.651)
			(layers "F.Cu" "F.Mask" "F.Paste")
			(net "P5V_A_2")
		)
	)
	(footprint ""
		(layer "F.Cu")
		(at 264.496042 -216.865962)
		(property "Reference" "U15"
			(at 0 0 0)
			(layer "F.SilkS")
			(hide yes)
			(effects
				(font
					(size 1.27 1.27)
				)
			)
		)
		(property "Value" "PCA9511ADP-T-GP"
			(at 0 -13.1572 0)
			(unlocked yes)
			(layer "F.Fab")
			(hide yes)
			(effects
				(font
					(size 1.016 1.016)
					(thickness 0.1524)
				)
			)
		)
		(property "Device Type" "SSOIC8-2H44"
			(at 0 -15.1892 0)
			(unlocked yes)
			(layer "F.Fab")
			(hide yes)
			(effects
				(font
					(size 1.016 1.016)
					(thickness 0.1524)
				)
			)
		)
		(duplicate_pad_numbers_are_jumpers no)
		(fp_line
			(start -1.9304 -1.016)
			(end 1.0922 -1.016)
			(stroke
				(width 0.1524)
				(type default)
			)
			(layer "F.SilkS")
		)
		(fp_line
			(start -1.9304 1.016)
			(end -1.9304 -1.016)
			(stroke
				(width 0.1524)
				(type default)
			)
			(layer "F.SilkS")
		)
		(fp_line
			(start -1.7018 1.0414)
			(end -1.7018 2.9718)
			(stroke
				(width 0.635)
				(type default)
			)
			(layer "F.SilkS")
		)
		(fp_line
			(start -1.524 0)
			(end -1.9304 -0.4064)
			(stroke
				(width 0.1524)
				(type default)
			)
			(layer "F.SilkS")
		)
		(fp_line
			(start -1.524 0)
			(end -1.9304 0.4064)
			(stroke
				(width 0.1524)
				(type default)
			)
			(layer "F.SilkS")
		)
		(fp_line
			(start 1.0922 -1.016)
			(end 1.0922 1.016)
			(stroke
				(width 0.1524)
				(type default)
			)
			(layer "F.SilkS")
		)
		(fp_line
			(start 1.0922 1.016)
			(end -1.9304 1.016)
			(stroke
				(width 0.1524)
				(type default)
			)
			(layer "F.SilkS")
		)
		(fp_poly
			(pts
				(xy -1.1938 -1.016) (xy 1.0922 -1.016) (xy 1.0922 1.016) (xy -1.1938 1.016)
			)
			(stroke
				(width 0)
				(type default)
			)
			(fill yes)
			(layer "F.SilkS")
		)
		(fp_rect
			(start -2.0066 3.3401)
			(end 2.0066 -3.3401)
			(stroke
				(width 0)
				(type default)
			)
			(fill no)
			(layer "F.CrtYd")
		)
		(fp_poly
			(pts
				(xy -2.0066 -3.3401) (xy 2.0066 -3.3401) (xy 2.0066 3.3401) (xy -2.0066 3.3401)
			)
			(stroke
				(width 0)
				(type default)
			)
			(fill no)
			(layer "F.Fab")
		)
		(pad "1" smd rect
			(at -0.97536 2.0701)
			(size 0.4064 1.524)
			(layers "F.Cu" "F.Mask" "F.Paste")
			(net "I2C_DPB_BUFF_EN")
		)
		(pad "2" smd rect
			(at -0.32512 2.0701)
			(size 0.4064 1.524)
			(layers "F.Cu" "F.Mask" "F.Paste")
			(net "I2C_DPB_A_SCL_BUF")
		)
		(pad "3" smd rect
			(at 0.32512 2.0701)
			(size 0.4064 1.524)
			(layers "F.Cu" "F.Mask" "F.Paste")
			(net "I2C_DPB_A_SCL")
		)
		(pad "4" smd rect
			(at 0.97536 2.0701)
			(size 0.4064 1.524)
			(layers "F.Cu" "F.Mask" "F.Paste")
			(net "GND")
		)
		(pad "5" smd rect
			(at 0.97536 -2.0701)
			(size 0.4064 1.524)
			(layers "F.Cu" "F.Mask" "F.Paste")
			(net "I2C_DPB_BUFF_READY")
		)
		(pad "6" smd rect
			(at 0.32512 -2.0701)
			(size 0.4064 1.524)
			(layers "F.Cu" "F.Mask" "F.Paste")
			(net "I2C_DPB_A_SDA")
		)
		(pad "7" smd rect
			(at -0.32512 -2.0701)
			(size 0.4064 1.524)
			(layers "F.Cu" "F.Mask" "F.Paste")
			(net "I2C_DPB_A_SDA_BUF")
		)
		(pad "8" smd rect
			(at -0.97536 -2.0701)
			(size 0.4064 1.524)
			(layers "F.Cu" "F.Mask" "F.Paste")
			(net "P3V3_STBY_A")
		)
	)
)
